(kicad_pcb
	(version 20260206)
	(generator "pcbnew")
	(generator_version "10.0")
	(general
		(thickness 1.6)
		(legacy_teardrops no)
	)
	(paper "A4")
	(title_block
		(title "baseboard — 13948-1b.1110WZS1818.brd")
		(comment 1 "Honey Badger (Wiwynn) / footprints 1703-1708 of 2523")
	)
	(layers
		(0 "F.Cu" signal "TOP")
		(4 "In1.Cu" signal "L2GND")
		(6 "In2.Cu" signal "L3")
		(8 "In3.Cu" signal "L4VCC")
		(10 "In4.Cu" signal "L5VCC")
		(12 "In5.Cu" signal "L6")
		(14 "In6.Cu" signal "L7GND")
		(2 "B.Cu" signal "BOTTOM")
		(9 "F.Adhes" user "F.Adhesive")
		(11 "B.Adhes" user "B.Adhesive")
		(13 "F.Paste" user "Package Geometry/Pastemask Top")
		(15 "B.Paste" user "Package Geometry/Pastemask Bottom")
		(5 "F.SilkS" user "Ref Des/Silkscreen Top")
		(7 "B.SilkS" user "Ref Des/Silkscreen Bottom")
		(1 "F.Mask" user "Board Geometry/Soldermask Top")
		(3 "B.Mask" user "Board Geometry/Soldermask Bottom")
		(17 "Dwgs.User" user "User.Drawings")
		(19 "Cmts.User" user "User.Comments")
		(21 "Eco1.User" user "User.Eco1")
		(23 "Eco2.User" user "User.Eco2")
		(25 "Edge.Cuts" user "Board Geometry/Outline")
		(27 "Margin" user)
		(31 "F.CrtYd" user "Package Geometry/Place Bound Top")
		(29 "B.CrtYd" user "Package Geometry/Place Bound Bottom")
		(35 "F.Fab" user "Ref Des/Assembly Top")
		(33 "B.Fab" user "Ref Des/Assembly Bottom")
	)
	(footprint ""
		(layer "F.Cu")
		(at 332.096872 -224.227136 180)
		(property "Reference" "U14"
			(at 0 0 180)
			(layer "F.SilkS")
			(hide yes)
			(effects
				(font
					(size 1.27 1.27)
				)
			)
		)
		(property "Value" "ADS1015IDGSR-GP"
			(at 0 -11.1252 180)
			(unlocked yes)
			(layer "F.Fab")
			(hide yes)
			(effects
				(font
					(size 1.016 1.016)
					(thickness 0.1524)
				)
			)
		)
		(property "Device Type" "MSOP10H44"
			(at 0 -12.6492 180)
			(unlocked yes)
			(layer "F.Fab")
			(hide yes)
			(effects
				(font
					(size 1.016 1.016)
					(thickness 0.1524)
				)
			)
		)
		(duplicate_pad_numbers_are_jumpers no)
		(fp_line
			(start 1.143 1.016)
			(end -2.0066 1.016)
			(stroke
				(width 0.1524)
				(type default)
			)
			(layer "F.SilkS")
		)
		(fp_line
			(start 1.143 -1.016)
			(end 1.143 1.016)
			(stroke
				(width 0.1524)
				(type default)
			)
			(layer "F.SilkS")
		)
		(fp_line
			(start -1.5748 0)
			(end -1.9558 0.381)
			(stroke
				(width 0.1524)
				(type default)
			)
			(layer "F.SilkS")
		)
		(fp_line
			(start -1.5748 0)
			(end -1.9558 -0.381)
			(stroke
				(width 0.1524)
				(type default)
			)
			(layer "F.SilkS")
		)
		(fp_line
			(start -1.8288 1.016)
			(end -1.8288 3.048)
			(stroke
				(width 0.508)
				(type default)
			)
			(layer "F.SilkS")
		)
		(fp_line
			(start -2.0066 1.016)
			(end -2.0066 -1.016)
			(stroke
				(width 0.1524)
				(type default)
			)
			(layer "F.SilkS")
		)
		(fp_line
			(start -2.0066 -1.016)
			(end 1.143 -1.016)
			(stroke
				(width 0.1524)
				(type default)
			)
			(layer "F.SilkS")
		)
		(fp_poly
			(pts
				(xy -2.0828 3.3401) (xy 2.0828 3.3401) (xy 2.0828 -3.3401) (xy -2.0828 -3.3401)
			)
			(stroke
				(width 0)
				(type default)
			)
			(fill no)
			(layer "F.CrtYd")
		)
		(fp_poly
			(pts
				(xy -2.0828 3.3401) (xy 2.0828 3.3401) (xy 2.0828 -3.3401) (xy -2.0828 -3.3401)
			)
			(stroke
				(width 0)
				(type default)
			)
			(fill no)
			(layer "F.Fab")
		)
		(pad "1" smd rect
			(at -0.99949 2.0701 180)
			(size 0.3048 1.524)
			(layers "F.Cu" "F.Mask" "F.Paste")
			(net "VOL_SEN_ADDR")
		)
		(pad "2" smd rect
			(at -0.50038 2.0701 180)
			(size 0.3048 1.524)
			(layers "F.Cu" "F.Mask" "F.Paste")
			(net "VOL_SEN_ALERT")
		)
		(pad "3" smd rect
			(at 0 2.0701 180)
			(size 0.3048 1.524)
			(layers "F.Cu" "F.Mask" "F.Paste")
			(net "GND")
		)
		(pad "4" smd rect
			(at 0.50038 2.0701 180)
			(size 0.3048 1.524)
			(layers "F.Cu" "F.Mask" "F.Paste")
			(net "12V_SENSE")
		)
		(pad "5" smd rect
			(at 0.99949 2.0701 180)
			(size 0.3048 1.524)
			(layers "F.Cu" "F.Mask" "F.Paste")
			(net "5V_STBY_SENSE")
		)
		(pad "6" smd rect
			(at 0.99949 -2.0701 180)
			(size 0.3048 1.524)
			(layers "F.Cu" "F.Mask" "F.Paste")
			(net "3V3_STBY_SENSE")
		)
		(pad "7" smd rect
			(at 0.50038 -2.0701 180)
			(size 0.3048 1.524)
			(layers "F.Cu" "F.Mask" "F.Paste")
			(net "1V8_STBY_SENSE")
		)
		(pad "8" smd rect
			(at 0 -2.0701 180)
			(size 0.3048 1.524)
			(layers "F.Cu" "F.Mask" "F.Paste")
			(net "P3V3_STBY")
		)
		(pad "9" smd rect
			(at -0.50038 -2.0701 180)
			(size 0.3048 1.524)
			(layers "F.Cu" "F.Mask" "F.Paste")
			(net "VOL_SEN_SDA")
		)
		(pad "10" smd rect
			(at -0.99949 -2.0701 180)
			(size 0.3048 1.524)
			(layers "F.Cu" "F.Mask" "F.Paste")
			(net "VOL_SEN_SCL")
		)
	)
	(footprint ""
		(layer "F.Cu")
		(at 267.772896 -74.106024 90)
		(property "Reference" "C259"
			(at 0 0 90)
			(layer "F.SilkS")
			(hide yes)
			(effects
				(font
					(size 1.27 1.27)
				)
			)
		)
		(property "Value" "SCD1U25V2KX-2-GP"
			(at 1.1811 -2.7051 90)
			(unlocked yes)
			(layer "F.Fab")
			(hide yes)
			(effects
				(font
					(size 1.016 1.016)
					(thickness 0.1524)
				)
			)
		)
		(property "Device Type" "C402H22"
			(at 1.1811 -4.2291 90)
			(unlocked yes)
			(layer "F.Fab")
			(hide yes)
			(effects
				(font
					(size 1.016 1.016)
					(thickness 0.1524)
				)
			)
		)
		(duplicate_pad_numbers_are_jumpers no)
		(fp_rect
			(start -0.4318 0.9525)
			(end 0.4318 -0.9525)
			(stroke
				(width 0)
				(type default)
			)
			(fill no)
			(layer "F.CrtYd")
		)
		(fp_rect
			(start -0.4318 0.9525)
			(end 0.4318 -0.9525)
			(stroke
				(width 0)
				(type default)
			)
			(fill no)
			(layer "F.Fab")
		)
		(pad "1" smd custom
			(at 0 -0.4445 90)
			(size 0.1524 0.1524)
			(layers "F.Cu" "F.Mask" "F.Paste")
			(net "P12V_MSB")
			(options
				(clearance outline)
				(anchor circle)
			)
			(primitives
				(gr_poly
					(pts
						(arc
							(start 0.3048 -0.2032)
							(mid 0.275042 -0.275042)
							(end 0.2032 -0.3048)
						)
						(arc
							(start -0.2032 -0.3048)
							(mid -0.275042 -0.275042)
							(end -0.3048 -0.2032)
						)
						(arc
							(start -0.3048 0.2032)
							(mid -0.275042 0.275042)
							(end -0.2032 0.3048)
						)
						(arc
							(start 0.2032 0.3048)
							(mid 0.275042 0.275042)
							(end 0.3048 0.2032)
						)
					)
					(width 0)
					(fill yes)
				)
			)
		)
		(pad "2" smd custom
			(at 0 0.4445 90)
			(size 0.1524 0.1524)
			(layers "F.Cu" "F.Mask" "F.Paste")
			(net "GND")
			(options
				(clearance outline)
				(anchor circle)
			)
			(primitives
				(gr_poly
					(pts
						(arc
							(start 0.3048 -0.2032)
							(mid 0.275042 -0.275042)
							(end 0.2032 -0.3048)
						)
						(arc
							(start -0.2032 -0.3048)
							(mid -0.275042 -0.275042)
							(end -0.3048 -0.2032)
						)
						(arc
							(start -0.3048 0.2032)
							(mid -0.275042 0.275042)
							(end -0.2032 0.3048)
						)
						(arc
							(start 0.2032 0.3048)
							(mid 0.275042 0.275042)
							(end 0.3048 0.2032)
						)
					)
					(width 0)
					(fill yes)
				)
			)
		)
	)
	(footprint ""
		(layer "F.Cu")
		(at 92.71 -3.683)
		(property "Reference" "PC199"
			(at 0 0 0)
			(layer "F.SilkS")
			(hide yes)
			(effects
				(font
					(size 1.27 1.27)
				)
			)
		)
		(property "Value" "SC22U6D3V6KX-2-GP"
			(at -0.0762 -5.1308 0)
			(unlocked yes)
			(layer "F.Fab")
			(hide yes)
			(effects
				(font
					(size 1.016 1.016)
					(thickness 0.1524)
				)
			)
		)
		(property "Device Type" "C1206H71"
			(at -0.127 -6.6548 0)
			(unlocked yes)
			(layer "F.Fab")
			(hide yes)
			(effects
				(font
					(size 1.016 1.016)
					(thickness 0.1524)
				)
			)
		)
		(duplicate_pad_numbers_are_jumpers no)
		(fp_line
			(start -1.016 -2.2352)
			(end 1.016 -2.2352)
			(stroke
				(width 0.1524)
				(type default)
			)
			(layer "F.SilkS")
		)
		(fp_line
			(start -1.016 -0.8382)
			(end -1.016 -2.2352)
			(stroke
				(width 0.1524)
				(type default)
			)
			(layer "F.SilkS")
		)
		(fp_line
			(start -1.016 2.2352)
			(end -1.016 0.8382)
			(stroke
				(width 0.1524)
				(type default)
			)
			(layer "F.SilkS")
		)
		(fp_line
			(start 1.016 -2.2352)
			(end 1.016 -0.8382)
			(stroke
				(width 0.1524)
				(type default)
			)
			(layer "F.SilkS")
		)
		(fp_line
			(start 1.016 0.8382)
			(end 1.016 2.2352)
			(stroke
				(width 0.1524)
				(type default)
			)
			(layer "F.SilkS")
		)
		(fp_line
			(start 1.016 2.2352)
			(end -1.016 2.2352)
			(stroke
				(width 0.1524)
				(type default)
			)
			(layer "F.SilkS")
		)
		(fp_rect
			(start -1.0922 2.3114)
			(end 1.0922 -2.3114)
			(stroke
				(width 0)
				(type default)
			)
			(fill no)
			(layer "F.CrtYd")
		)
		(fp_poly
			(pts
				(xy 1.0922 -2.3114) (xy 1.0922 2.3114) (xy -1.0922 2.3114) (xy -1.0922 -2.3114)
			)
			(stroke
				(width 0)
				(type default)
			)
			(fill no)
			(layer "F.Fab")
		)
		(pad "1" smd rect
			(at 0 -1.397)
			(size 1.651 1.27)
			(layers "F.Cu" "F.Mask" "F.Paste")
			(net "P0V955_C")
		)
		(pad "2" smd rect
			(at 0 1.397)
			(size 1.651 1.27)
			(layers "F.Cu" "F.Mask" "F.Paste")
			(net "GND")
		)
	)
	(footprint ""
		(layer "F.Cu")
		(at 326.517 -118.491 180)
		(property "Reference" "PC24"
			(at 0 0 180)
			(layer "F.SilkS")
			(hide yes)
			(effects
				(font
					(size 1.27 1.27)
				)
			)
		)
		(property "Value" "SC22U25V5MX-GP"
			(at -0.0762 -6.1214 180)
			(unlocked yes)
			(layer "F.Fab")
			(hide yes)
			(effects
				(font
					(size 1.016 1.016)
					(thickness 0.1524)
				)
			)
		)
		(property "Device Type" "C805H58"
			(at -0.0762 -8.1534 180)
			(unlocked yes)
			(layer "F.Fab")
			(hide yes)
			(effects
				(font
					(size 1.016 1.016)
					(thickness 0.1524)
				)
			)
		)
		(duplicate_pad_numbers_are_jumpers no)
		(fp_line
			(start 0.635 0)
			(end -0.635 0)
			(stroke
				(width 0.508)
				(type default)
			)
			(layer "F.SilkS")
		)
		(fp_rect
			(start -0.9652 1.778)
			(end 0.9652 -1.778)
			(stroke
				(width 0)
				(type default)
			)
			(fill no)
			(layer "F.CrtYd")
		)
		(fp_poly
			(pts
				(xy -0.9652 -1.778) (xy 0.9652 -1.778) (xy 0.9652 1.778) (xy -0.9652 1.778)
			)
			(stroke
				(width 0)
				(type default)
			)
			(fill no)
			(layer "F.Fab")
		)
		(pad "1" smd rect
			(at 0 -0.9652 180)
			(size 1.397 1.143)
			(layers "F.Cu" "F.Mask" "F.Paste")
			(net "P3V3_STBY_VIN")
		)
		(pad "2" smd rect
			(at 0 0.9652 180)
			(size 1.397 1.143)
			(layers "F.Cu" "F.Mask" "F.Paste")
			(net "GND")
		)
	)
	(footprint ""
		(layer "F.Cu")
		(at 196.111876 -146.549872 -90)
		(property "Reference" "SU68"
			(at 0 0 270)
			(layer "F.SilkS")
			(hide yes)
			(effects
				(font
					(size 1.27 1.27)
				)
			)
		)
		(property "Value" "PCA9306DCTT-GP"
			(at 0 -11.6332 270)
			(unlocked yes)
			(layer "F.Fab")
			(hide yes)
			(effects
				(font
					(size 1.016 1.016)
					(thickness 0.1524)
				)
			)
		)
		(property "Device Type" "SSOIC8H52"
			(at 0 -13.1572 270)
			(unlocked yes)
			(layer "F.Fab")
			(hide yes)
			(effects
				(font
					(size 1.016 1.016)
					(thickness 0.1524)
				)
			)
		)
		(duplicate_pad_numbers_are_jumpers no)
		(fp_line
			(start -1.524 0.5842)
			(end -1.524 2.286)
			(stroke
				(width 0.508)
				(type default)
			)
			(layer "F.SilkS")
		)
		(fp_line
			(start 1.0668 0.5842)
			(end -1.524 0.5842)
			(stroke
				(width 0.1524)
				(type default)
			)
			(layer "F.SilkS")
		)
		(fp_line
			(start -1.397 0)
			(end -1.7018 0.3048)
			(stroke
				(width 0.1524)
				(type default)
			)
			(layer "F.SilkS")
		)
		(fp_line
			(start -1.397 0)
			(end -1.7018 -0.3048)
			(stroke
				(width 0.1524)
				(type default)
			)
			(layer "F.SilkS")
		)
		(fp_line
			(start -1.7018 -0.5842)
			(end -1.7018 2.286)
			(stroke
				(width 0.1524)
				(type default)
			)
			(layer "F.SilkS")
		)
		(fp_line
			(start -1.7018 -0.5842)
			(end 1.0668 -0.5842)
			(stroke
				(width 0.1524)
				(type default)
			)
			(layer "F.SilkS")
		)
		(fp_line
			(start 1.0668 -0.5842)
			(end 1.0668 0.5842)
			(stroke
				(width 0.1524)
				(type default)
			)
			(layer "F.SilkS")
		)
		(fp_poly
			(pts
				(xy -1.1684 -0.5842) (xy 1.0668 -0.5842) (xy 1.0668 0.5842) (xy -1.1684 0.5842)
			)
			(stroke
				(width 0)
				(type default)
			)
			(fill yes)
			(layer "F.SilkS")
		)
		(fp_poly
			(pts
				(xy -1.778 2.54) (xy 1.778 2.54) (xy 1.778 -2.54) (xy -1.778 -2.54)
			)
			(stroke
				(width 0)
				(type default)
			)
			(fill no)
			(layer "F.CrtYd")
		)
		(fp_poly
			(pts
				(xy -1.778 -2.54) (xy 1.778 -2.54) (xy 1.778 2.54) (xy -1.778 2.54)
			)
			(stroke
				(width 0)
				(type default)
			)
			(fill no)
			(layer "F.Fab")
		)
		(pad "1" smd rect
			(at -0.97536 1.6256 270)
			(size 0.3556 1.524)
			(layers "F.Cu" "F.Mask" "F.Paste")
			(net "GND")
		)
		(pad "2" smd rect
			(at -0.32512 1.6256 270)
			(size 0.3556 1.524)
			(layers "F.Cu" "F.Mask" "F.Paste")
			(net "P1V8_E")
		)
		(pad "3" smd rect
			(at 0.32512 1.6256 270)
			(size 0.3556 1.524)
			(layers "F.Cu" "F.Mask" "F.Paste")
			(net "EXP_I2C_SCL_3")
		)
		(pad "4" smd rect
			(at 0.97536 1.6256 270)
			(size 0.3556 1.524)
			(layers "F.Cu" "F.Mask" "F.Paste")
			(net "EXP_I2C_SDA_3")
		)
		(pad "5" smd rect
			(at 0.97536 -1.6256 270)
			(size 0.3556 1.524)
			(layers "F.Cu" "F.Mask" "F.Paste")
			(net "BMC_I2C_SDA_9")
		)
		(pad "6" smd rect
			(at 0.32512 -1.6256 270)
			(size 0.3556 1.524)
			(layers "F.Cu" "F.Mask" "F.Paste")
			(net "BMC_I2C_SCL_9")
		)
		(pad "7" smd rect
			(at -0.32512 -1.6256 270)
			(size 0.3556 1.524)
			(layers "F.Cu" "F.Mask" "F.Paste")
			(net "EXP_I2C_VREF_2")
		)
		(pad "8" smd rect
			(at -0.97536 -1.6256 270)
			(size 0.3556 1.524)
			(layers "F.Cu" "F.Mask" "F.Paste")
			(net "EXP_I2C_VREF_2")
		)
	)
	(footprint ""
		(layer "F.Cu")
		(at 258.699 -126.746 180)
		(property "Reference" "R9025"
			(at 0 0 180)
			(layer "F.SilkS")
			(hide yes)
			(effects
				(font
					(size 1.27 1.27)
				)
			)
		)
		(property "Value" "4K7R3F-GP"
			(at -0.0254 -2.5146 180)
			(unlocked yes)
			(layer "F.Fab")
			(hide yes)
			(effects
				(font
					(size 1.016 1.016)
					(thickness 0.1524)
				)
			)
		)
		(property "Device Type" "R603H22"
			(at -0.0254 -4.0386 180)
			(unlocked yes)
			(layer "F.Fab")
			(hide yes)
			(effects
				(font
					(size 1.016 1.016)
					(thickness 0.1524)
				)
			)
		)
		(duplicate_pad_numbers_are_jumpers no)
		(fp_line
			(start 0.2032 0)
			(end 0.4826 0)
			(stroke
				(width 0.2032)
				(type default)
			)
			(layer "F.SilkS")
		)
		(fp_line
			(start -0.4826 0)
			(end -0.2032 0)
			(stroke
				(width 0.2032)
				(type default)
			)
			(layer "F.SilkS")
		)
		(fp_rect
			(start -0.5842 1.3335)
			(end 0.5842 -1.3335)
			(stroke
				(width 0)
				(type default)
			)
			(fill no)
			(layer "F.CrtYd")
		)
		(fp_rect
			(start -0.5842 1.3335)
			(end 0.5842 -1.3335)
			(stroke
				(width 0)
				(type default)
			)
			(fill no)
			(layer "F.Fab")
		)
		(pad "1" smd custom
			(at 0 -0.762 180)
			(size 0.2159 0.2159)
			(layers "F.Cu" "F.Mask" "F.Paste")
			(net "P3V3_STBY")
			(options
				(clearance outline)
				(anchor circle)
			)
			(primitives
				(gr_poly
					(pts
						(arc
							(start -0.3302 -0.4318)
							(mid -0.402042 -0.402042)
							(end -0.4318 -0.3302)
						)
						(arc
							(start -0.4318 0.3302)
							(mid -0.402042 0.402042)
							(end -0.3302 0.4318)
						)
						(arc
							(start 0.3302 0.4318)
							(mid 0.402042 0.402042)
							(end 0.4318 0.3302)
						)
						(arc
							(start 0.4318 -0.3302)
							(mid 0.402042 -0.402042)
							(end 0.3302 -0.4318)
						)
					)
					(width 0)
					(fill yes)
				)
			)
		)
		(pad "2" smd custom
			(at 0 0.762 180)
			(size 0.2159 0.2159)
			(layers "F.Cu" "F.Mask" "F.Paste")
			(net "CPU_U192_PIN5_RX")
			(options
				(clearance outline)
				(anchor circle)
			)
			(primitives
				(gr_poly
					(pts
						(arc
							(start -0.3302 -0.4318)
							(mid -0.402042 -0.402042)
							(end -0.4318 -0.3302)
						)
						(arc
							(start -0.4318 0.3302)
							(mid -0.402042 0.402042)
							(end -0.3302 0.4318)
						)
						(arc
							(start 0.3302 0.4318)
							(mid 0.402042 0.402042)
							(end 0.4318 0.3302)
						)
						(arc
							(start 0.4318 -0.3302)
							(mid 0.402042 -0.402042)
							(end 0.3302 -0.4318)
						)
					)
					(width 0)
					(fill yes)
				)
			)
		)
	)
)
